(kicad_pcb
	(version 20260206)
	(generator "pcbnew")
	(generator_version "10.0")
	(general
		(thickness 1.6)
		(legacy_teardrops no)
	)
	(paper "A4")
	(title_block
		(title "Wiwynn_Tioga_Pass_MB.brd")
		(comment 1 "Tioga Pass / footprints 1466-1473 of 4770")
	)
	(layers
		(0 "F.Cu" signal "TOP")
		(4 "In1.Cu" signal "L2GND")
		(6 "In2.Cu" signal "L3")
		(8 "In3.Cu" signal "L4GND")
		(10 "In4.Cu" signal "L5")
		(12 "In5.Cu" signal "L6GND")
		(14 "In6.Cu" signal "L7VCC")
		(16 "In7.Cu" signal "L8VCC")
		(18 "In8.Cu" signal "L9GND")
		(20 "In9.Cu" signal "L10")
		(22 "In10.Cu" signal "L11GND")
		(24 "In11.Cu" signal "L12")
		(26 "In12.Cu" signal "L13GND")
		(2 "B.Cu" signal "BOTTOM")
		(9 "F.Adhes" user "F.Adhesive")
		(11 "B.Adhes" user "B.Adhesive")
		(13 "F.Paste" user "Package Geometry/Pastemask Top")
		(15 "B.Paste" user "Package Geometry/Pastemask Bottom")
		(5 "F.SilkS" user "Ref Des/Silkscreen Top")
		(7 "B.SilkS" user "Ref Des/Silkscreen Bottom")
		(1 "F.Mask" user "Board Geometry/Soldermask Top")
		(3 "B.Mask" user "Board Geometry/Soldermask Bottom")
		(17 "Dwgs.User" user "User.Drawings")
		(19 "Cmts.User" user "User.Comments")
		(21 "Eco1.User" user "User.Eco1")
		(23 "Eco2.User" user "User.Eco2")
		(25 "Edge.Cuts" user "Board Geometry/Outline")
		(27 "Margin" user)
		(31 "F.CrtYd" user "Package Geometry/Place Bound Top")
		(29 "B.CrtYd" user "Package Geometry/Place Bound Bottom")
		(35 "F.Fab" user "Ref Des/Assembly Top")
		(33 "B.Fab" user "Ref Des/Assembly Bottom")
	)
	(footprint ""
		(layer "F.Cu")
		(at 353.427284 -96.501204 -90)
		(property "Reference" "RT47"
			(at 1.01473 0.656336 180)
			(unlocked yes)
			(layer "F.SilkS")
			(effects
				(font
					(size 0.4064 0.254)
					(thickness 0.1524)
				)
			)
		)
		(property "Value" ""
			(at 0 0 270)
			(layer "F.Fab")
			(effects
				(font
					(size 1.27 1.27)
				)
			)
		)
		(duplicate_pad_numbers_are_jumpers no)
		(fp_poly
			(pts
				(xy -0.4953 -0.2032) (xy 0.4953 -0.2032) (xy 0.4953 1.6002) (xy -0.4953 1.6002)
			)
			(stroke
				(width 0)
				(type default)
			)
			(fill no)
			(layer "F.CrtYd")
		)
		(fp_line
			(start -0.4953 1.6002)
			(end -0.4953 -0.2032)
			(stroke
				(width 0.1)
				(type default)
			)
			(layer "F.Fab")
		)
		(fp_line
			(start 0.4953 1.6002)
			(end -0.4953 1.6002)
			(stroke
				(width 0.1)
				(type default)
			)
			(layer "F.Fab")
		)
		(fp_line
			(start -0.4953 -0.2032)
			(end 0.4953 -0.2032)
			(stroke
				(width 0.1)
				(type default)
			)
			(layer "F.Fab")
		)
		(fp_line
			(start 0.4953 -0.2032)
			(end 0.4953 1.6002)
			(stroke
				(width 0.1)
				(type default)
			)
			(layer "F.Fab")
		)
		(pad "1" smd rect
			(at 0 0 270)
			(size 0.762 0.889)
			(layers "F.Cu" "F.Mask" "F.Paste")
			(net "VR_PVCCIO_CPU0_PH1_BOOT")
		)
		(pad "2" smd rect
			(at 0 1.397 270)
			(size 0.762 0.889)
			(layers "F.Cu" "F.Mask" "F.Paste")
			(net "VR_PVCCIO_CPU0_PH1_BOOT_R")
		)
		(zone
			(layer "F.Cu")
			(hatch none 0.5)
			(connect_pads
				(clearance 0)
			)
			(min_thickness 0.25)
			(keepout
				(tracks not_allowed)
				(vias allowed)
				(pads allowed)
				(copperpour not_allowed)
				(footprints allowed)
			)
			(placement
				(enabled no)
				(sheetname "")
			)
			(fill
				(thermal_gap 0.5)
				(thermal_bridge_width 0.5)
				(island_removal_mode 0)
			)
			(polygon
				(pts
					(xy 352.474784 -96.882204) (xy 352.474784 -96.120204) (xy 352.982784 -96.120204) (xy 352.982784 -96.882204)
				)
			)
		)
		(zone
			(layer "F.Cu")
			(hatch none 0.5)
			(connect_pads
				(clearance 0)
			)
			(min_thickness 0.25)
			(keepout
				(tracks allowed)
				(vias not_allowed)
				(pads allowed)
				(copperpour not_allowed)
				(footprints allowed)
			)
			(placement
				(enabled no)
				(sheetname "")
			)
			(fill
				(thermal_gap 0.5)
				(thermal_bridge_width 0.5)
				(island_removal_mode 0)
			)
			(polygon
				(pts
					(xy 352.474784 -96.120204) (xy 352.982784 -96.120204) (xy 352.982784 -96.882204) (xy 352.474784 -96.882204)
				)
			)
		)
	)
	(footprint ""
		(layer "F.Cu")
		(at 417.481766 -22.049232)
		(property "Reference" "R1U13"
			(at 0 0 0)
			(layer "F.SilkS")
			(hide yes)
			(effects
				(font
					(size 1.27 1.27)
				)
			)
		)
		(property "Value" ""
			(at 0 0 0)
			(layer "F.Fab")
			(effects
				(font
					(size 1.27 1.27)
				)
			)
		)
		(duplicate_pad_numbers_are_jumpers no)
		(fp_poly
			(pts
				(xy -0.2794 -0.1016) (xy 0.2794 -0.1016) (xy 0.2794 0.9906) (xy -0.2794 0.9906)
			)
			(stroke
				(width 0)
				(type default)
			)
			(fill no)
			(layer "F.CrtYd")
		)
		(fp_line
			(start -0.2794 -0.1016)
			(end -0.2794 0.9906)
			(stroke
				(width 0.1)
				(type default)
			)
			(layer "F.Fab")
		)
		(fp_line
			(start -0.2794 0.9906)
			(end 0.2794 0.9906)
			(stroke
				(width 0.1)
				(type default)
			)
			(layer "F.Fab")
		)
		(fp_line
			(start 0.2794 -0.1016)
			(end -0.2794 -0.1016)
			(stroke
				(width 0.1)
				(type default)
			)
			(layer "F.Fab")
		)
		(fp_line
			(start 0.2794 0.9906)
			(end 0.2794 -0.1016)
			(stroke
				(width 0.1)
				(type default)
			)
			(layer "F.Fab")
		)
		(pad "1" smd rect
			(at 0 0)
			(size 0.508 0.508)
			(layers "F.Cu" "F.Mask" "F.Paste")
			(net "SGPIO_BMC_DOUT_R")
		)
		(pad "2" smd rect
			(at 0 0.889)
			(size 0.508 0.508)
			(layers "F.Cu" "F.Mask" "F.Paste")
			(net "SGPIO_BMC_DOUT")
		)
		(zone
			(layer "F.Cu")
			(hatch none 0.5)
			(connect_pads
				(clearance 0)
			)
			(min_thickness 0.25)
			(keepout
				(tracks allowed)
				(vias not_allowed)
				(pads allowed)
				(copperpour not_allowed)
				(footprints allowed)
			)
			(placement
				(enabled no)
				(sheetname "")
			)
			(fill
				(thermal_gap 0.5)
				(thermal_bridge_width 0.5)
				(island_removal_mode 0)
			)
			(polygon
				(pts
					(xy 417.227766 -21.795232) (xy 417.735766 -21.795232) (xy 417.735766 -21.414232) (xy 417.227766 -21.414232)
				)
			)
		)
		(zone
			(layer "F.Cu")
			(hatch none 0.5)
			(connect_pads
				(clearance 0)
			)
			(min_thickness 0.25)
			(keepout
				(tracks not_allowed)
				(vias allowed)
				(pads allowed)
				(copperpour not_allowed)
				(footprints allowed)
			)
			(placement
				(enabled no)
				(sheetname "")
			)
			(fill
				(thermal_gap 0.5)
				(thermal_bridge_width 0.5)
				(island_removal_mode 0)
			)
			(polygon
				(pts
					(xy 417.227766 -21.414232) (xy 417.735766 -21.414232) (xy 417.735766 -21.795232) (xy 417.227766 -21.795232)
				)
			)
		)
	)
	(footprint ""
		(layer "F.Cu")
		(at 106.89844 -77.636116)
		(property "Reference" "C3D10"
			(at 0 0 0)
			(layer "F.SilkS")
			(hide yes)
			(effects
				(font
					(size 1.27 1.27)
				)
			)
		)
		(property "Value" ""
			(at 0 0 0)
			(layer "F.Fab")
			(effects
				(font
					(size 1.27 1.27)
				)
			)
		)
		(duplicate_pad_numbers_are_jumpers no)
		(fp_poly
			(pts
				(xy -0.4953 -0.2032) (xy 0.4953 -0.2032) (xy 0.4953 1.6002) (xy -0.4953 1.6002)
			)
			(stroke
				(width 0)
				(type default)
			)
			(fill no)
			(layer "F.CrtYd")
		)
		(fp_line
			(start -0.4953 -0.2032)
			(end 0.4953 -0.2032)
			(stroke
				(width 0.1)
				(type default)
			)
			(layer "F.Fab")
		)
		(fp_line
			(start -0.4953 1.6002)
			(end -0.4953 -0.2032)
			(stroke
				(width 0.1)
				(type default)
			)
			(layer "F.Fab")
		)
		(fp_line
			(start 0.4953 -0.2032)
			(end 0.4953 1.6002)
			(stroke
				(width 0.1)
				(type default)
			)
			(layer "F.Fab")
		)
		(fp_line
			(start 0.4953 1.6002)
			(end -0.4953 1.6002)
			(stroke
				(width 0.1)
				(type default)
			)
			(layer "F.Fab")
		)
		(pad "1" smd rect
			(at 0 0)
			(size 0.762 0.889)
			(layers "F.Cu" "F.Mask" "F.Paste")
			(net "PVCCMCP_CPU1")
		)
		(pad "2" smd rect
			(at 0 1.397)
			(size 0.762 0.889)
			(layers "F.Cu" "F.Mask" "F.Paste")
			(net "GND")
		)
		(zone
			(layer "F.Cu")
			(hatch none 0.5)
			(connect_pads
				(clearance 0)
			)
			(min_thickness 0.25)
			(keepout
				(tracks not_allowed)
				(vias allowed)
				(pads allowed)
				(copperpour not_allowed)
				(footprints allowed)
			)
			(placement
				(enabled no)
				(sheetname "")
			)
			(fill
				(thermal_gap 0.5)
				(thermal_bridge_width 0.5)
				(island_removal_mode 0)
			)
			(polygon
				(pts
					(xy 106.51744 -77.191616) (xy 107.27944 -77.191616) (xy 107.27944 -76.683616) (xy 106.51744 -76.683616)
				)
			)
		)
	)
	(footprint ""
		(layer "F.Cu")
		(at 403.6314 -128.3335)
		(property "Reference" "C7D3"
			(at 0 0 0)
			(layer "F.SilkS")
			(hide yes)
			(effects
				(font
					(size 1.27 1.27)
				)
			)
		)
		(property "Value" ""
			(at 0 0 0)
			(layer "F.Fab")
			(effects
				(font
					(size 1.27 1.27)
				)
			)
		)
		(duplicate_pad_numbers_are_jumpers no)
		(fp_poly
			(pts
				(xy -0.4953 -0.2032) (xy 0.4953 -0.2032) (xy 0.4953 1.6002) (xy -0.4953 1.6002)
			)
			(stroke
				(width 0)
				(type default)
			)
			(fill no)
			(layer "F.CrtYd")
		)
		(fp_line
			(start -0.4953 -0.2032)
			(end 0.4953 -0.2032)
			(stroke
				(width 0.1)
				(type default)
			)
			(layer "F.Fab")
		)
		(fp_line
			(start -0.4953 1.6002)
			(end -0.4953 -0.2032)
			(stroke
				(width 0.1)
				(type default)
			)
			(layer "F.Fab")
		)
		(fp_line
			(start 0.4953 -0.2032)
			(end 0.4953 1.6002)
			(stroke
				(width 0.1)
				(type default)
			)
			(layer "F.Fab")
		)
		(fp_line
			(start 0.4953 1.6002)
			(end -0.4953 1.6002)
			(stroke
				(width 0.1)
				(type default)
			)
			(layer "F.Fab")
		)
		(pad "1" smd rect
			(at 0 0)
			(size 0.762 0.889)
			(layers "F.Cu" "F.Mask" "F.Paste")
			(net "P1V8_PCH_STBY")
		)
		(pad "2" smd rect
			(at 0 1.397)
			(size 0.762 0.889)
			(layers "F.Cu" "F.Mask" "F.Paste")
			(net "GND")
		)
		(zone
			(layer "F.Cu")
			(hatch none 0.5)
			(connect_pads
				(clearance 0)
			)
			(min_thickness 0.25)
			(keepout
				(tracks not_allowed)
				(vias allowed)
				(pads allowed)
				(copperpour not_allowed)
				(footprints allowed)
			)
			(placement
				(enabled no)
				(sheetname "")
			)
			(fill
				(thermal_gap 0.5)
				(thermal_bridge_width 0.5)
				(island_removal_mode 0)
			)
			(polygon
				(pts
					(xy 403.2504 -127.889) (xy 404.0124 -127.889) (xy 404.0124 -127.381) (xy 403.2504 -127.381)
				)
			)
		)
	)
	(footprint ""
		(layer "F.Cu")
		(at 14.097 -79.4385 180)
		(property "Reference" "R1D28"
			(at 0 0 180)
			(layer "F.SilkS")
			(hide yes)
			(effects
				(font
					(size 1.27 1.27)
				)
			)
		)
		(property "Value" ""
			(at 0 0 180)
			(layer "F.Fab")
			(effects
				(font
					(size 1.27 1.27)
				)
			)
		)
		(duplicate_pad_numbers_are_jumpers no)
		(fp_poly
			(pts
				(xy -0.2794 -0.1016) (xy 0.2794 -0.1016) (xy 0.2794 0.9906) (xy -0.2794 0.9906)
			)
			(stroke
				(width 0)
				(type default)
			)
			(fill no)
			(layer "F.CrtYd")
		)
		(fp_line
			(start 0.2794 0.9906)
			(end 0.2794 -0.1016)
			(stroke
				(width 0.1)
				(type default)
			)
			(layer "F.Fab")
		)
		(fp_line
			(start 0.2794 -0.1016)
			(end -0.2794 -0.1016)
			(stroke
				(width 0.1)
				(type default)
			)
			(layer "F.Fab")
		)
		(fp_line
			(start -0.2794 0.9906)
			(end 0.2794 0.9906)
			(stroke
				(width 0.1)
				(type default)
			)
			(layer "F.Fab")
		)
		(fp_line
			(start -0.2794 -0.1016)
			(end -0.2794 0.9906)
			(stroke
				(width 0.1)
				(type default)
			)
			(layer "F.Fab")
		)
		(pad "1" smd rect
			(at 0 0 180)
			(size 0.508 0.508)
			(layers "F.Cu" "F.Mask" "F.Paste")
			(net "PD_HSC_RETRY_N")
		)
		(pad "2" smd rect
			(at 0 0.889 180)
			(size 0.508 0.508)
			(layers "F.Cu" "F.Mask" "F.Paste")
			(net "AGND_HSC")
		)
		(zone
			(layer "F.Cu")
			(hatch none 0.5)
			(connect_pads
				(clearance 0)
			)
			(min_thickness 0.25)
			(keepout
				(tracks not_allowed)
				(vias allowed)
				(pads allowed)
				(copperpour not_allowed)
				(footprints allowed)
			)
			(placement
				(enabled no)
				(sheetname "")
			)
			(fill
				(thermal_gap 0.5)
				(thermal_bridge_width 0.5)
				(island_removal_mode 0)
			)
			(polygon
				(pts
					(xy 14.351 -80.0735) (xy 13.843 -80.0735) (xy 13.843 -79.6925) (xy 14.351 -79.6925)
				)
			)
		)
		(zone
			(layer "F.Cu")
			(hatch none 0.5)
			(connect_pads
				(clearance 0)
			)
			(min_thickness 0.25)
			(keepout
				(tracks allowed)
				(vias not_allowed)
				(pads allowed)
				(copperpour not_allowed)
				(footprints allowed)
			)
			(placement
				(enabled no)
				(sheetname "")
			)
			(fill
				(thermal_gap 0.5)
				(thermal_bridge_width 0.5)
				(island_removal_mode 0)
			)
			(polygon
				(pts
					(xy 14.351 -79.6925) (xy 13.843 -79.6925) (xy 13.843 -80.0735) (xy 14.351 -80.0735)
				)
			)
		)
	)
	(footprint ""
		(layer "F.Cu")
		(at 438.531 -12.954 180)
		(property "Reference" "R1U56"
			(at 0 0 180)
			(layer "F.SilkS")
			(hide yes)
			(effects
				(font
					(size 1.27 1.27)
				)
			)
		)
		(property "Value" ""
			(at 0 0 180)
			(layer "F.Fab")
			(effects
				(font
					(size 1.27 1.27)
				)
			)
		)
		(duplicate_pad_numbers_are_jumpers no)
		(fp_poly
			(pts
				(xy -0.2794 -0.1016) (xy 0.2794 -0.1016) (xy 0.2794 0.9906) (xy -0.2794 0.9906)
			)
			(stroke
				(width 0)
				(type default)
			)
			(fill no)
			(layer "F.CrtYd")
		)
		(fp_line
			(start 0.2794 0.9906)
			(end 0.2794 -0.1016)
			(stroke
				(width 0.1)
				(type default)
			)
			(layer "F.Fab")
		)
		(fp_line
			(start 0.2794 -0.1016)
			(end -0.2794 -0.1016)
			(stroke
				(width 0.1)
				(type default)
			)
			(layer "F.Fab")
		)
		(fp_line
			(start -0.2794 0.9906)
			(end 0.2794 0.9906)
			(stroke
				(width 0.1)
				(type default)
			)
			(layer "F.Fab")
		)
		(fp_line
			(start -0.2794 -0.1016)
			(end -0.2794 0.9906)
			(stroke
				(width 0.1)
				(type default)
			)
			(layer "F.Fab")
		)
		(pad "1" smd rect
			(at 0 0 180)
			(size 0.508 0.508)
			(layers "F.Cu" "F.Mask" "F.Paste")
			(net "H_CPU0_MEMDEF_MEMHOT_G_PCH_N")
		)
		(pad "2" smd rect
			(at 0 0.889 180)
			(size 0.508 0.508)
			(layers "F.Cu" "F.Mask" "F.Paste")
			(net "H_CPU0_MEMDEF_MEMHOT_G_N")
		)
		(zone
			(layer "F.Cu")
			(hatch none 0.5)
			(connect_pads
				(clearance 0)
			)
			(min_thickness 0.25)
			(keepout
				(tracks not_allowed)
				(vias allowed)
				(pads allowed)
				(copperpour not_allowed)
				(footprints allowed)
			)
			(placement
				(enabled no)
				(sheetname "")
			)
			(fill
				(thermal_gap 0.5)
				(thermal_bridge_width 0.5)
				(island_removal_mode 0)
			)
			(polygon
				(pts
					(xy 438.785 -13.589) (xy 438.277 -13.589) (xy 438.277 -13.208) (xy 438.785 -13.208)
				)
			)
		)
		(zone
			(layer "F.Cu")
			(hatch none 0.5)
			(connect_pads
				(clearance 0)
			)
			(min_thickness 0.25)
			(keepout
				(tracks allowed)
				(vias not_allowed)
				(pads allowed)
				(copperpour not_allowed)
				(footprints allowed)
			)
			(placement
				(enabled no)
				(sheetname "")
			)
			(fill
				(thermal_gap 0.5)
				(thermal_bridge_width 0.5)
				(island_removal_mode 0)
			)
			(polygon
				(pts
					(xy 438.785 -13.208) (xy 438.277 -13.208) (xy 438.277 -13.589) (xy 438.785 -13.589)
				)
			)
		)
	)
	(footprint ""
		(layer "F.Cu")
		(at 396.875 -149.0472)
		(property "Reference" "R2L16"
			(at 0 0 0)
			(layer "F.SilkS")
			(hide yes)
			(effects
				(font
					(size 1.27 1.27)
				)
			)
		)
		(property "Value" ""
			(at 0 0 0)
			(layer "F.Fab")
			(effects
				(font
					(size 1.27 1.27)
				)
			)
		)
		(duplicate_pad_numbers_are_jumpers no)
		(fp_poly
			(pts
				(xy -0.2794 -0.1016) (xy 0.2794 -0.1016) (xy 0.2794 0.9906) (xy -0.2794 0.9906)
			)
			(stroke
				(width 0)
				(type default)
			)
			(fill no)
			(layer "F.CrtYd")
		)
		(fp_line
			(start -0.2794 -0.1016)
			(end -0.2794 0.9906)
			(stroke
				(width 0.1)
				(type default)
			)
			(layer "F.Fab")
		)
		(fp_line
			(start -0.2794 0.9906)
			(end 0.2794 0.9906)
			(stroke
				(width 0.1)
				(type default)
			)
			(layer "F.Fab")
		)
		(fp_line
			(start 0.2794 -0.1016)
			(end -0.2794 -0.1016)
			(stroke
				(width 0.1)
				(type default)
			)
			(layer "F.Fab")
		)
		(fp_line
			(start 0.2794 0.9906)
			(end 0.2794 -0.1016)
			(stroke
				(width 0.1)
				(type default)
			)
			(layer "F.Fab")
		)
		(pad "1" smd rect
			(at 0 0)
			(size 0.508 0.508)
			(layers "F.Cu" "F.Mask" "F.Paste")
			(net "PWRGD_PVNN_PCH_R")
		)
		(pad "2" smd rect
			(at 0 0.889)
			(size 0.508 0.508)
			(layers "F.Cu" "F.Mask" "F.Paste")
			(net "PWRGD_PVNN_P1V05_PCH")
		)
		(zone
			(layer "F.Cu")
			(hatch none 0.5)
			(connect_pads
				(clearance 0)
			)
			(min_thickness 0.25)
			(keepout
				(tracks allowed)
				(vias not_allowed)
				(pads allowed)
				(copperpour not_allowed)
				(footprints allowed)
			)
			(placement
				(enabled no)
				(sheetname "")
			)
			(fill
				(thermal_gap 0.5)
				(thermal_bridge_width 0.5)
				(island_removal_mode 0)
			)
			(polygon
				(pts
					(xy 396.621 -148.7932) (xy 397.129 -148.7932) (xy 397.129 -148.4122) (xy 396.621 -148.4122)
				)
			)
		)
		(zone
			(layer "F.Cu")
			(hatch none 0.5)
			(connect_pads
				(clearance 0)
			)
			(min_thickness 0.25)
			(keepout
				(tracks not_allowed)
				(vias allowed)
				(pads allowed)
				(copperpour not_allowed)
				(footprints allowed)
			)
			(placement
				(enabled no)
				(sheetname "")
			)
			(fill
				(thermal_gap 0.5)
				(thermal_bridge_width 0.5)
				(island_removal_mode 0)
			)
			(polygon
				(pts
					(xy 396.621 -148.4122) (xy 397.129 -148.4122) (xy 397.129 -148.7932) (xy 396.621 -148.7932)
				)
			)
		)
	)
	(footprint ""
		(layer "F.Cu")
		(at 2.4003 -114.554 -90)
		(property "Reference" "R10W7"
			(at -0.8382 -0.67818 270)
			(unlocked yes)
			(layer "F.SilkS")
			(effects
				(font
					(size 0.4064 0.254)
					(thickness 0.1524)
				)
				(justify left)
			)
		)
		(property "Value" ""
			(at 0 0 270)
			(layer "F.Fab")
			(effects
				(font
					(size 1.27 1.27)
				)
			)
		)
		(duplicate_pad_numbers_are_jumpers no)
		(fp_poly
			(pts
				(xy -0.2794 -0.1016) (xy 0.2794 -0.1016) (xy 0.2794 0.9906) (xy -0.2794 0.9906)
			)
			(stroke
				(width 0)
				(type default)
			)
			(fill no)
			(layer "F.CrtYd")
		)
		(fp_line
			(start -0.2794 0.9906)
			(end 0.2794 0.9906)
			(stroke
				(width 0.1)
				(type default)
			)
			(layer "F.Fab")
		)
		(fp_line
			(start 0.2794 0.9906)
			(end 0.2794 -0.1016)
			(stroke
				(width 0.1)
				(type default)
			)
			(layer "F.Fab")
		)
		(fp_line
			(start -0.2794 -0.1016)
			(end -0.2794 0.9906)
			(stroke
				(width 0.1)
				(type default)
			)
			(layer "F.Fab")
		)
		(fp_line
			(start 0.2794 -0.1016)
			(end -0.2794 -0.1016)
			(stroke
				(width 0.1)
				(type default)
			)
			(layer "F.Fab")
		)
		(pad "1" smd rect
			(at 0 0 270)
			(size 0.508 0.508)
			(layers "F.Cu" "F.Mask" "F.Paste")
			(net "P3V3_STBY")
		)
		(pad "2" smd rect
			(at 0 0.889 270)
			(size 0.508 0.508)
			(layers "F.Cu" "F.Mask" "F.Paste")
			(net "PUMP_TACH1")
		)
		(zone
			(layer "F.Cu")
			(hatch none 0.5)
			(connect_pads
				(clearance 0)
			)
			(min_thickness 0.25)
			(keepout
				(tracks not_allowed)
				(vias allowed)
				(pads allowed)
				(copperpour not_allowed)
				(footprints allowed)
			)
			(placement
				(enabled no)
				(sheetname "")
			)
			(fill
				(thermal_gap 0.5)
				(thermal_bridge_width 0.5)
				(island_removal_mode 0)
			)
			(polygon
				(pts
					(xy 1.7653 -114.808) (xy 1.7653 -114.3) (xy 2.1463 -114.3) (xy 2.1463 -114.808)
				)
			)
		)
		(zone
			(layer "F.Cu")
			(hatch none 0.5)
			(connect_pads
				(clearance 0)
			)
			(min_thickness 0.25)
			(keepout
				(tracks allowed)
				(vias not_allowed)
				(pads allowed)
				(copperpour not_allowed)
				(footprints allowed)
			)
			(placement
				(enabled no)
				(sheetname "")
			)
			(fill
				(thermal_gap 0.5)
				(thermal_bridge_width 0.5)
				(island_removal_mode 0)
			)
			(polygon
				(pts
					(xy 2.1463 -114.808) (xy 2.1463 -114.3) (xy 1.7653 -114.3) (xy 1.7653 -114.808)
				)
			)
		)
	)
)
